# Jetson Orin Baseboard — KiCad project settings (.kicad_pro: net classes, design rules, text variables)
{
  "board": {
    "3dviewports": [],
    "design_settings": {
      "defaults": {
        "apply_defaults_to_fp_fields": false,
        "apply_defaults_to_fp_shapes": false,
        "apply_defaults_to_fp_text": false,
        "board_outline_line_width": 0.1,
        "copper_line_width": 0.2,
        "copper_text_italic": false,
        "copper_text_size_h": 1.5,
        "copper_text_size_v": 1.5,
        "copper_text_thickness": 0.3,
        "copper_text_upright": false,
        "courtyard_line_width": 0.05,
        "dimension_precision": 4,
        "dimension_units": 3,
        "dimensions": {
          "arrow_length": 1270000,
          "extension_offset": 500000,
          "keep_text_aligned": true,
          "suppress_zeroes": false,
          "text_position": 0,
          "units_format": 1
        },
        "fab_line_width": 0.1,
        "fab_text_italic": false,
        "fab_text_size_h": 1.0,
        "fab_text_size_v": 1.0,
        "fab_text_thickness": 0.15,
        "fab_text_upright": false,
        "other_line_width": 0.15,
        "other_text_italic": false,
        "other_text_size_h": 1.0,
        "other_text_size_v": 1.0,
        "other_text_thickness": 0.15,
        "other_text_upright": false,
        "pads": {
          "drill": 0.0,
          "height": 1.0,
          "width": 1.0
        },
        "silk_line_width": 0.15,
        "silk_text_italic": false,
        "silk_text_size_h": 1.0,
        "silk_text_size_v": 1.0,
        "silk_text_thickness": 0.15,
        "silk_text_upright": false,
        "zones": {
          "45_degree_only": false,
          "min_clearance": 0.3
        }
      },
      "diff_pair_dimensions": [
        {
          "gap": 0.0,
          "via_gap": 0.0,
          "width": 0.0
        }
      ],
      "drc_exclusions": [],
      "meta": {
        "version": 2
      },
      "rule_severities": {
        "annular_width": "error",
        "clearance": "error",
        "connection_width": "warning",
        "copper_edge_clearance": "error",
        "copper_sliver": "warning",
        "courtyards_overlap": "error",
        "diff_pair_gap_out_of_range": "error",
        "diff_pair_uncoupled_length_too_long": "error",
        "drill_out_of_range": "error",
        "duplicate_footprints": "warning",
        "extra_footprint": "warning",
        "footprint": "error",
        "footprint_symbol_mismatch": "warning",
        "footprint_type_mismatch": "ignore",
        "hole_clearance": "error",
        "hole_near_hole": "error",
        "holes_co_located": "error",
        "invalid_outline": "error",
        "isolated_copper": "warning",
        "item_on_disabled_layer": "error",
        "items_not_allowed": "error",
        "length_out_of_range": "error",
        "lib_footprint_issues": "warning",
        "lib_footprint_mismatch": "warning",
        "malformed_courtyard": "error",
        "microvia_drill_out_of_range": "error",
        "missing_courtyard": "warning",
        "missing_footprint": "warning",
        "net_conflict": "warning",
        "npth_inside_courtyard": "warning",
        "padstack": "error",
        "pth_inside_courtyard": "warning",
        "shorting_items": "error",
        "silk_edge_clearance": "warning",
        "silk_over_copper": "warning",
        "silk_overlap": "warning",
        "skew_out_of_range": "error",
        "solder_mask_bridge": "error",
        "starved_thermal": "error",
        "text_height": "warning",
        "text_thickness": "warning",
        "through_hole_pad_without_hole": "error",
        "too_many_vias": "error",
        "track_dangling": "warning",
        "track_width": "error",
        "tracks_crossing": "error",
        "unconnected_items": "error",
        "unresolved_variable": "error",
        "via_dangling": "warning",
        "zones_intersect": "error"
      },
      "rules": {
        "allow_blind_buried_vias": false,
        "allow_microvias": false,
        "max_error": 0.005,
        "min_clearance": 0.125,
        "min_connection": 0.0,
        "min_copper_edge_clearance": 0.4,
        "min_hole_clearance": 0.125,
        "min_hole_to_hole": 0.25,
        "min_microvia_diameter": 0.2,
        "min_microvia_drill": 0.1,
        "min_resolved_spokes": 1,
        "min_silk_clearance": 0.0,
        "min_text_height": 0.6,
        "min_text_thickness": 0.0,
        "min_through_hole_diameter": 0.1,
        "min_track_width": 0.125,
        "min_via_annular_width": 0.125,
        "min_via_diameter": 0.45,
        "solder_mask_clearance": 0.0,
        "solder_mask_min_width": 0.0,
        "solder_mask_to_copper_clearance": 0.0,
        "use_height_for_length_calcs": true
      },
      "teardrop_options": [
        {
          "td_onpadsmd": true,
          "td_onroundshapesonly": false,
          "td_ontrackend": false,
          "td_onviapad": true
        }
      ],
      "teardrop_parameters": [
        {
          "td_allow_use_two_tracks": true,
          "td_curve_segcount": 0,
          "td_height_ratio": 1.0,
          "td_length_ratio": 0.5,
          "td_maxheight": 2.0,
          "td_maxlen": 1.0,
          "td_on_pad_in_zone": false,
          "td_target_name": "td_round_shape",
          "td_width_to_size_filter_ratio": 0.9
        },
        {
          "td_allow_use_two_tracks": true,
          "td_curve_segcount": 0,
          "td_height_ratio": 1.0,
          "td_length_ratio": 0.5,
          "td_maxheight": 2.0,
          "td_maxlen": 1.0,
          "td_on_pad_in_zone": false,
          "td_target_name": "td_rect_shape",
          "td_width_to_size_filter_ratio": 0.9
        },
        {
          "td_allow_use_two_tracks": true,
          "td_curve_segcount": 0,
          "td_height_ratio": 1.0,
          "td_length_ratio": 0.5,
          "td_maxheight": 2.0,
          "td_maxlen": 1.0,
          "td_on_pad_in_zone": false,
          "td_target_name": "td_track_end",
          "td_width_to_size_filter_ratio": 0.9
        }
      ],
      "track_widths": [
        0.0,
        0.125,
        0.13,
        0.155,
        0.16,
        0.2,
        0.3,
        0.5,
        1.4,
        4.0
      ],
      "tuning_pattern_settings": {
        "diff_pair_defaults": {
          "corner_radius_percentage": 80,
          "corner_style": 1,
          "max_amplitude": 1.0,
          "min_amplitude": 0.2,
          "single_sided": false,
          "spacing": 1.0
        },
        "diff_pair_skew_defaults": {
          "corner_radius_percentage": 80,
          "corner_style": 1,
          "max_amplitude": 1.0,
          "min_amplitude": 0.2,
          "single_sided": false,
          "spacing": 0.6
        },
        "single_track_defaults": {
          "corner_radius_percentage": 80,
          "corner_style": 1,
          "max_amplitude": 1.0,
          "min_amplitude": 0.2,
          "single_sided": false,
          "spacing": 0.6
        }
      },
      "via_dimensions": [
        {
          "diameter": 0.0,
          "drill": 0.0
        },
        {
          "diameter": 0.4,
          "drill": 0.1
        },
        {
          "diameter": 1.0,
          "drill": 0.5
        }
      ],
      "zones_allow_external_fillets": false,
      "zones_use_no_outline": true
    },
    "ipc2581": {
      "dist": "",
      "distpn": "",
      "internal_id": "",
      "mfg": "",
      "mpn": ""
    },
    "layer_presets": [],
    "viewports": []
  },
  "boards": [],
  "cvpcb": {
    "equivalence_files": []
  },
  "erc": {
    "erc_exclusions": [],
    "meta": {
      "version": 0
    },
    "pin_map": [
      [
        0,
        0,
        0,
        0,
        0,
        0,
        1,
        0,
        0,
        0,
        0,
        2
      ],
      [
        0,
        2,
        0,
        1,
        0,
        0,
        1,
        0,
        2,
        2,
        2,
        2
      ],
      [
        0,
        0,
        0,
        0,
        0,
        0,
        1,
        0,
        1,
        0,
        1,
        2
      ],
      [
        0,
        1,
        0,
        0,
        0,
        0,
        1,
        1,
        2,
        1,
        1,
        2
      ],
      [
        0,
        0,
        0,
        0,
        0,
        0,
        1,
        0,
        0,
        0,
        0,
        2
      ],
      [
        0,
        0,
        0,
        0,
        0,
        0,
        0,
        0,
        0,
        0,
        0,
        2
      ],
      [
        1,
        1,
        1,
        1,
        1,
        0,
        1,
        1,
        1,
        1,
        1,
        2
      ],
      [
        0,
        0,
        0,
        1,
        0,
        0,
        1,
        0,
        0,
        0,
        0,
        2
      ],
      [
        0,
        2,
        1,
        2,
        0,
        0,
        1,
        0,
        2,
        2,
        2,
        2
      ],
      [
        0,
        2,
        0,
        1,
        0,
        0,
        1,
        0,
        2,
        0,
        0,
        2
      ],
      [
        0,
        2,
        1,
        1,
        0,
        0,
        1,
        0,
        2,
        0,
        0,
        2
      ],
      [
        2,
        2,
        2,
        2,
        2,
        2,
        2,
        2,
        2,
        2,
        2,
        2
      ]
    ],
    "rule_severities": {
      "bus_definition_conflict": "error",
      "bus_entry_needed": "error",
      "bus_to_bus_conflict": "error",
      "bus_to_net_conflict": "error",
      "conflicting_netclasses": "error",
      "different_unit_footprint": "error",
      "different_unit_net": "error",
      "duplicate_reference": "error",
      "duplicate_sheet_names": "error",
      "endpoint_off_grid": "warning",
      "extra_units": "error",
      "global_label_dangling": "warning",
      "hier_label_mismatch": "error",
      "label_dangling": "error",
      "lib_symbol_issues": "warning",
      "missing_bidi_pin": "warning",
      "missing_input_pin": "warning",
      "missing_power_pin": "error",
      "missing_unit": "warning",
      "multiple_net_names": "warning",
      "net_not_bus_member": "warning",
      "no_connect_connected": "error",
      "no_connect_dangling": "warning",
      "pin_not_connected": "error",
      "pin_not_driven": "error",
      "pin_to_pin": "ignore",
      "power_pin_not_driven": "error",
      "similar_labels": "warning",
      "simulation_model_issue": "ignore",
      "unannotated": "error",
      "unit_value_mismatch": "error",
      "unresolved_variable": "error",
      "wire_dangling": "error"
    }
  },
  "libraries": {
    "pinned_footprint_libs": [],
    "pinned_symbol_libs": []
  },
  "meta": {
    "filename": "jetson-orin-baseboard.kicad_pro",
    "version": 1
  },
  "net_settings": {
    "classes": [
      {
        "bus_width": 12,
        "clearance": 0.125,
        "diff_pair_gap": 0.25,
        "diff_pair_via_gap": 0.25,
        "diff_pair_width": 0.2,
        "line_style": 0,
        "microvia_diameter": 0.45,
        "microvia_drill": 0.1,
        "name": "Default",
        "pcb_color": "rgba(0, 0, 0, 0.000)",
        "schematic_color": "rgba(0, 0, 0, 0.000)",
        "track_width": 0.15,
        "via_diameter": 0.45,
        "via_drill": 0.1,
        "wire_width": 6
      },
      {
        "bus_width": 12,
        "clearance": 0.125,
        "diff_pair_gap": 0.25,
        "diff_pair_via_gap": 0.25,
        "diff_pair_width": 0.2,
        "line_style": 0,
        "microvia_diameter": 0.45,
        "microvia_drill": 0.1,
        "name": "100Ohm-diff_HDMI",
        "pcb_color": "rgba(0, 0, 0, 0.000)",
        "schematic_color": "rgba(0, 0, 0, 0.000)",
        "track_width": 0.15,
        "via_diameter": 0.45,
        "via_drill": 0.1,
        "wire_width": 6
      },
      {
        "bus_width": 12,
        "clearance": 0.125,
        "diff_pair_gap": 0.25,
        "diff_pair_via_gap": 0.25,
        "diff_pair_width": 0.2,
        "line_style": 0,
        "microvia_diameter": 0.45,
        "microvia_drill": 0.1,
        "name": "100Ohm-diff_MDI",
        "pcb_color": "rgba(0, 0, 0, 0.000)",
        "schematic_color": "rgba(0, 0, 0, 0.000)",
        "track_width": 0.15,
        "via_diameter": 0.45,
        "via_drill": 0.1,
        "wire_width": 6
      },
      {
        "bus_width": 12,
        "clearance": 0.125,
        "diff_pair_gap": 0.25,
        "diff_pair_via_gap": 0.25,
        "diff_pair_width": 0.2,
        "line_style": 0,
        "microvia_diameter": 0.45,
        "microvia_drill": 0.1,
        "name": "85Ohm-diff_CSI",
        "pcb_color": "rgba(0, 0, 0, 0.000)",
        "schematic_color": "rgba(0, 0, 0, 0.000)",
        "track_width": 0.15,
        "via_diameter": 0.45,
        "via_drill": 0.1,
        "wire_width": 6
      },
      {
        "bus_width": 12,
        "clearance": 0.125,
        "diff_pair_gap": 0.25,
        "diff_pair_via_gap": 0.25,
        "diff_pair_width": 0.2,
        "line_style": 0,
        "microvia_diameter": 0.45,
        "microvia_drill": 0.1,
        "name": "85Ohm-diff_PCIE",
        "pcb_color": "rgba(0, 0, 0, 0.000)",
        "schematic_color": "rgba(0, 0, 0, 0.000)",
        "track_width": 0.15,
        "via_diameter": 0.45,
        "via_drill": 0.1,
        "wire_width": 6
      },
      {
        "bus_width": 12,
        "clearance": 0.125,
        "diff_pair_gap": 0.25,
        "diff_pair_via_gap": 0.25,
        "diff_pair_width": 0.2,
        "line_style": 0,
        "microvia_diameter": 0.45,
        "microvia_drill": 0.1,
        "name": "85Ohm-diff_USB_2.0",
        "pcb_color": "rgba(0, 0, 0, 0.000)",
        "schematic_color": "rgba(0, 0, 0, 0.000)",
        "track_width": 0.15,
        "via_diameter": 0.45,
        "via_drill": 0.1,
        "wire_width": 6
      },
      {
        "bus_width": 12,
        "clearance": 0.125,
        "diff_pair_gap": 0.25,
        "diff_pair_via_gap": 0.25,
        "diff_pair_width": 0.2,
        "line_style": 0,
        "microvia_diameter": 0.45,
        "microvia_drill": 0.1,
        "name": "85Ohm-diff_USB_SS",
        "pcb_color": "rgba(0, 0, 0, 0.000)",
        "schematic_color": "rgba(0, 0, 0, 0.000)",
        "track_width": 0.15,
        "via_diameter": 0.45,
        "via_drill": 0.1,
        "wire_width": 6
      },
      {
        "bus_width": 12,
        "clearance": 0.125,
        "diff_pair_gap": 0.25,
        "diff_pair_via_gap": 0.25,
        "diff_pair_width": 0.2,
        "line_style": 0,
        "microvia_diameter": 0.45,
        "microvia_drill": 0.1,
        "name": "PoE",
        "pcb_color": "rgba(0, 0, 0, 0.000)",
        "schematic_color": "rgba(0, 0, 0, 0.000)",
        "track_width": 0.15,
        "via_diameter": 0.45,
        "via_drill": 0.1,
        "wire_width": 6
      }
    ],
    "meta": {
      "version": 3
    },
    "net_colors": null,
    "netclass_assignments": {
      "Net-(D12-Pad1)": "PoE",
      "Net-(D12-Pad2)": "PoE",
      "Net-(D15-A)": "PoE",
      "Net-(J6-P4)": "PoE",
      "Net-(R155-Pad2)": "PoE"
    },
    "netclass_patterns": [
      {
        "netclass": "100Ohm-diff_HDMI",
        "pattern": "/HDMI/DP_MUX_AUX_A+"
      },
      {
        "netclass": "100Ohm-diff_HDMI",
        "pattern": "/HDMI/DP_MUX_AUX_A-"
      },
      {
        "netclass": "100Ohm-diff_HDMI",
        "pattern": "/HDMI/DP_MUX_AUX_B+"
      },
      {
        "netclass": "100Ohm-diff_HDMI",
        "pattern": "/HDMI/DP_MUX_AUX_B-"
      },
      {
        "netclass": "100Ohm-diff_HDMI",
        "pattern": "/HDMI/DP_MUX_D0+"
      },
      {
        "netclass": "100Ohm-diff_HDMI",
        "pattern": "/HDMI/DP_MUX_D0-"
      },
      {
        "netclass": "100Ohm-diff_HDMI",
        "pattern": "/HDMI/DP_MUX_D1+"
      },
      {
        "netclass": "100Ohm-diff_HDMI",
        "pattern": "/HDMI/DP_MUX_D1-"
      },
      {
        "netclass": "100Ohm-diff_HDMI",
        "pattern": "/HDMI/DP_MUX_D2+"
      },
      {
        "netclass": "100Ohm-diff_HDMI",
        "pattern": "/HDMI/DP_MUX_D2-"
      },
      {
        "netclass": "100Ohm-diff_HDMI",
        "pattern": "/HDMI/DP_MUX_D3+"
      },
      {
        "netclass": "100Ohm-diff_HDMI",
        "pattern": "/HDMI/DP_MUX_D3-"
      },
      {
        "netclass": "100Ohm-diff_HDMI",
        "pattern": "/HDMI/HDMI_CLK_CONN_N"
      },
      {
        "netclass": "100Ohm-diff_HDMI",
        "pattern": "/HDMI/HDMI_CLK_CONN_P"
      },
      {
        "netclass": "100Ohm-diff_HDMI",
        "pattern": "/HDMI/HDMI_CLK_N"
      },
      {
        "netclass": "100Ohm-diff_HDMI",
        "pattern": "/HDMI/HDMI_CLK_P"
      },
      {
        "netclass": "100Ohm-diff_HDMI",
        "pattern": "/HDMI/HDMI_D0_CONN_N"
      },
      {
        "netclass": "100Ohm-diff_HDMI",
        "pattern": "/HDMI/HDMI_D0_CONN_P"
      },
      {
        "netclass": "100Ohm-diff_HDMI",
        "pattern": "/HDMI/HDMI_D0_N"
      },
      {
        "netclass": "100Ohm-diff_HDMI",
        "pattern": "/HDMI/HDMI_D0_P"
      },
      {
        "netclass": "100Ohm-diff_HDMI",
        "pattern": "/HDMI/HDMI_D1_CONN_N"
      },
      {
        "netclass": "100Ohm-diff_HDMI",
        "pattern": "/HDMI/HDMI_D1_CONN_P"
      },
      {
        "netclass": "100Ohm-diff_HDMI",
        "pattern": "/HDMI/HDMI_D1_N"
      },
      {
        "netclass": "100Ohm-diff_HDMI",
        "pattern": "/HDMI/HDMI_D1_P"
      },
      {
        "netclass": "100Ohm-diff_HDMI",
        "pattern": "/HDMI/HDMI_D2_CONN_N"
      },
      {
        "netclass": "100Ohm-diff_HDMI",
        "pattern": "/HDMI/HDMI_D2_CONN_P"
      },
      {
        "netclass": "100Ohm-diff_HDMI",
        "pattern": "/HDMI/HDMI_D2_N"
      },
      {
        "netclass": "100Ohm-diff_HDMI",
        "pattern": "/HDMI/HDMI_D2_P"
      },
      {
        "netclass": "100Ohm-diff_HDMI",
        "pattern": "DP1_AUX_N"
      },
      {
        "netclass": "100Ohm-diff_HDMI",
        "pattern": "DP1_AUX_P"
      },
      {
        "netclass": "100Ohm-diff_HDMI",
        "pattern": "DP1_HDMI_AUX_N"
      },
      {
        "netclass": "100Ohm-diff_HDMI",
        "pattern": "DP1_HDMI_AUX_P"
      },
      {
        "netclass": "100Ohm-diff_HDMI",
        "pattern": "DP1_TXD0_HDMI_TX2_N"
      },
      {
        "netclass": "100Ohm-diff_HDMI",
        "pattern": "DP1_TXD0_HDMI_TX2_P"
      },
      {
        "netclass": "100Ohm-diff_HDMI",
        "pattern": "DP1_TXD0_N"
      },
      {
        "netclass": "100Ohm-diff_HDMI",
        "pattern": "DP1_TXD0_P"
      },
      {
        "netclass": "100Ohm-diff_HDMI",
        "pattern": "DP1_TXD1_HDMI_TX1_N"
      },
      {
        "netclass": "100Ohm-diff_HDMI",
        "pattern": "DP1_TXD1_HDMI_TX1_P"
      },
      {
        "netclass": "100Ohm-diff_HDMI",
        "pattern": "DP1_TXD1_N"
      },
      {
        "netclass": "100Ohm-diff_HDMI",
        "pattern": "DP1_TXD1_P"
      },
      {
        "netclass": "100Ohm-diff_HDMI",
        "pattern": "DP1_TXD2_HDMI_TX0_N"
      },
      {
        "netclass": "100Ohm-diff_HDMI",
        "pattern": "DP1_TXD2_HDMI_TX0_P"
      },
      {
        "netclass": "100Ohm-diff_HDMI",
        "pattern": "DP1_TXD2_N"
      },
      {
        "netclass": "100Ohm-diff_HDMI",
        "pattern": "DP1_TXD2_P"
      },
      {
        "netclass": "100Ohm-diff_HDMI",
        "pattern": "DP1_TXD3_HDMI_TXC_N"
      },
      {
        "netclass": "100Ohm-diff_HDMI",
        "pattern": "DP1_TXD3_HDMI_TXC_P"
      },
      {
        "netclass": "100Ohm-diff_HDMI",
        "pattern": "DP1_TXD3_N"
      },
      {
        "netclass": "100Ohm-diff_HDMI",
        "pattern": "DP1_TXD3_P"
      },
      {
        "netclass": "100Ohm-diff_MDI",
        "pattern": "GBE_MDI0_N"
      },
      {
        "netclass": "100Ohm-diff_MDI",
        "pattern": "GBE_MDI0_P"
      },
      {
        "netclass": "100Ohm-diff_MDI",
        "pattern": "GBE_MDI1_N"
      },
      {
        "netclass": "100Ohm-diff_MDI",
        "pattern": "GBE_MDI1_P"
      },
      {
        "netclass": "100Ohm-diff_MDI",
        "pattern": "GBE_MDI2_N"
      },
      {
        "netclass": "100Ohm-diff_MDI",
        "pattern": "GBE_MDI2_P"
      },
      {
        "netclass": "100Ohm-diff_MDI",
        "pattern": "GBE_MDI3_N"
      },
      {
        "netclass": "100Ohm-diff_MDI",
        "pattern": "GBE_MDI3_P"
      },
      {
        "netclass": "85Ohm-diff_CSI",
        "pattern": "/CSI/CSI1_0_D0_N"
      },
      {
        "netclass": "85Ohm-diff_CSI",
        "pattern": "/CSI/CSI1_0_D0_P"
      },
      {
        "netclass": "85Ohm-diff_CSI",
        "pattern": "/CSI/CSI1_0_D1_N"
      },
      {
        "netclass": "85Ohm-diff_CSI",
        "pattern": "/CSI/CSI1_0_D1_P"
      },
      {
        "netclass": "85Ohm-diff_CSI",
        "pattern": "/CSI/CSI1_1_D0_N"
      },
      {
        "netclass": "85Ohm-diff_CSI",
        "pattern": "/CSI/CSI1_1_D0_P"
      },
      {
        "netclass": "85Ohm-diff_CSI",
        "pattern": "/CSI/CSI1_1_D1_N"
      },
      {
        "netclass": "85Ohm-diff_CSI",
        "pattern": "/CSI/CSI1_1_D1_P"
      },
      {
        "netclass": "85Ohm-diff_CSI",
        "pattern": "/CSI/CSI3_0_D0_N"
      },
      {
        "netclass": "85Ohm-diff_CSI",
        "pattern": "/CSI/CSI3_0_D0_P"
      },
      {
        "netclass": "85Ohm-diff_CSI",
        "pattern": "/CSI/CSI3_0_D1_N"
      },
      {
        "netclass": "85Ohm-diff_CSI",
        "pattern": "/CSI/CSI3_0_D1_P"
      },
      {
        "netclass": "85Ohm-diff_CSI",
        "pattern": "/CSI/CSI3_1_D0_N"
      },
      {
        "netclass": "85Ohm-diff_CSI",
        "pattern": "/CSI/CSI3_1_D0_P"
      },
      {
        "netclass": "85Ohm-diff_CSI",
        "pattern": "/CSI/CSI3_1_D1_N"
      },
      {
        "netclass": "85Ohm-diff_CSI",
        "pattern": "/CSI/CSI3_1_D1_P"
      },
      {
        "netclass": "85Ohm-diff_CSI",
        "pattern": "CSI0_CLK_N"
      },
      {
        "netclass": "85Ohm-diff_CSI",
        "pattern": "CSI0_CLK_P"
      },
      {
        "netclass": "85Ohm-diff_CSI",
        "pattern": "CSI0_D0_N"
      },
      {
        "netclass": "85Ohm-diff_CSI",
        "pattern": "CSI0_D0_P"
      },
      {
        "netclass": "85Ohm-diff_CSI",
        "pattern": "CSI0_D1_N"
      },
      {
        "netclass": "85Ohm-diff_CSI",
        "pattern": "CSI0_D1_P"
      },
      {
        "netclass": "85Ohm-diff_CSI",
        "pattern": "CSI1_CLK_N"
      },
      {
        "netclass": "85Ohm-diff_CSI",
        "pattern": "CSI1_CLK_P"
      },
      {
        "netclass": "85Ohm-diff_CSI",
        "pattern": "CSI1_D0_N"
      },
      {
        "netclass": "85Ohm-diff_CSI",
        "pattern": "CSI1_D0_P"
      },
      {
        "netclass": "85Ohm-diff_CSI",
        "pattern": "CSI1_D1_N"
      },
      {
        "netclass": "85Ohm-diff_CSI",
        "pattern": "CSI1_D1_P"
      },
      {
        "netclass": "85Ohm-diff_CSI",
        "pattern": "CSI2_CLK_N"
      },
      {
        "netclass": "85Ohm-diff_CSI",
        "pattern": "CSI2_CLK_P"
      },
      {
        "netclass": "85Ohm-diff_CSI",
        "pattern": "CSI2_D0_N"
      },
      {
        "netclass": "85Ohm-diff_CSI",
        "pattern": "CSI2_D0_P"
      },
      {
        "netclass": "85Ohm-diff_CSI",
        "pattern": "CSI2_D1_N"
      },
      {
        "netclass": "85Ohm-diff_CSI",
        "pattern": "CSI2_D1_P"
      },
      {
        "netclass": "85Ohm-diff_CSI",
        "pattern": "CSI3_CLK_N"
      },
      {
        "netclass": "85Ohm-diff_CSI",
        "pattern": "CSI3_CLK_P"
      },
      {
        "netclass": "85Ohm-diff_CSI",
        "pattern": "CSI3_D0_N"
      },
      {
        "netclass": "85Ohm-diff_CSI",
        "pattern": "CSI3_D0_P"
      },
      {
        "netclass": "85Ohm-diff_CSI",
        "pattern": "CSI3_D1_N"
      },
      {
        "netclass": "85Ohm-diff_CSI",
        "pattern": "CSI3_D1_P"
      },
      {
        "netclass": "85Ohm-diff_PCIE",
        "pattern": "/M.2/C_PCIE0_TX0_N"
      },
      {
        "netclass": "85Ohm-diff_PCIE",
        "pattern": "/M.2/C_PCIE0_TX0_P"
      },
      {
        "netclass": "85Ohm-diff_PCIE",
        "pattern": "/M.2/C_PCIE0_TX1_N"
      },
      {
        "netclass": "85Ohm-diff_PCIE",
        "pattern": "/M.2/C_PCIE0_TX1_P"
      },
      {
        "netclass": "85Ohm-diff_PCIE",
        "pattern": "/M.2/C_PCIE0_TX2_N"
      },
      {
        "netclass": "85Ohm-diff_PCIE",
        "pattern": "/M.2/C_PCIE0_TX2_P"
      },
      {
        "netclass": "85Ohm-diff_PCIE",
        "pattern": "/M.2/C_PCIE0_TX3_N"
      },
      {
        "netclass": "85Ohm-diff_PCIE",
        "pattern": "/M.2/C_PCIE0_TX3_P"
      },
      {
        "netclass": "85Ohm-diff_PCIE",
        "pattern": "/M.2/C_PCIE1_TX0_N"
      },
      {
        "netclass": "85Ohm-diff_PCIE",
        "pattern": "/M.2/C_PCIE1_TX0_P"
      },
      {
        "netclass": "85Ohm-diff_PCIE",
        "pattern": "/Peripherals/PCIE2_TX0_CONN_N"
      },
      {
        "netclass": "85Ohm-diff_PCIE",
        "pattern": "/Peripherals/PCIE2_TX0_CONN_P"
      },
      {
        "netclass": "85Ohm-diff_PCIE",
        "pattern": "/Peripherals/PCIE2_TX1_CONN_N"
      },
      {
        "netclass": "85Ohm-diff_PCIE",
        "pattern": "/Peripherals/PCIE2_TX1_CONN_P"
      },
      {
        "netclass": "85Ohm-diff_PCIE",
        "pattern": "PCIE0_CLK_N"
      },
      {
        "netclass": "85Ohm-diff_PCIE",
        "pattern": "PCIE0_CLK_P"
      },
      {
        "netclass": "85Ohm-diff_PCIE",
        "pattern": "PCIE0_RX0_N"
      },
      {
        "netclass": "85Ohm-diff_PCIE",
        "pattern": "PCIE0_RX0_P"
      },
      {
        "netclass": "85Ohm-diff_PCIE",
        "pattern": "PCIE0_RX1_N"
      },
      {
        "netclass": "85Ohm-diff_PCIE",
        "pattern": "PCIE0_RX1_P"
      },
      {
        "netclass": "85Ohm-diff_PCIE",
        "pattern": "PCIE0_RX2_N"
      },
      {
        "netclass": "85Ohm-diff_PCIE",
        "pattern": "PCIE0_RX2_P"
      },
      {
        "netclass": "85Ohm-diff_PCIE",
        "pattern": "PCIE0_RX3_N"
      },
      {
        "netclass": "85Ohm-diff_PCIE",
        "pattern": "PCIE0_RX3_P"
      },
      {
        "netclass": "85Ohm-diff_PCIE",
        "pattern": "PCIE0_TX0_N"
      },
      {
        "netclass": "85Ohm-diff_PCIE",
        "pattern": "PCIE0_TX0_P"
      },
      {
        "netclass": "85Ohm-diff_PCIE",
        "pattern": "PCIE0_TX1_N"
      },
      {
        "netclass": "85Ohm-diff_PCIE",
        "pattern": "PCIE0_TX1_P"
      },
      {
        "netclass": "85Ohm-diff_PCIE",
        "pattern": "PCIE0_TX2_N"
      },
      {
        "netclass": "85Ohm-diff_PCIE",
        "pattern": "PCIE0_TX2_P"
      },
      {
        "netclass": "85Ohm-diff_PCIE",
        "pattern": "PCIE0_TX3_N"
      },
      {
        "netclass": "85Ohm-diff_PCIE",
        "pattern": "PCIE0_TX3_P"
      },
      {
        "netclass": "85Ohm-diff_PCIE",
        "pattern": "PCIE1_CLK_N"
      },
      {
        "netclass": "85Ohm-diff_PCIE",
        "pattern": "PCIE1_CLK_P"
      },
      {
        "netclass": "85Ohm-diff_PCIE",
        "pattern": "PCIE1_RX0_N"
      },
      {
        "netclass": "85Ohm-diff_PCIE",
        "pattern": "PCIE1_RX0_P"
      },
      {
        "netclass": "85Ohm-diff_PCIE",
        "pattern": "PCIE1_TX0_N"
      },
      {
        "netclass": "85Ohm-diff_PCIE",
        "pattern": "PCIE1_TX0_P"
      },
      {
        "netclass": "85Ohm-diff_PCIE",
        "pattern": "PCIE2_CLK_N"
      },
      {
        "netclass": "85Ohm-diff_PCIE",
        "pattern": "PCIE2_CLK_P"
      },
      {
        "netclass": "85Ohm-diff_PCIE",
        "pattern": "PCIE2_RX0_N"
      },
      {
        "netclass": "85Ohm-diff_PCIE",
        "pattern": "PCIE2_RX0_P"
      },
      {
        "netclass": "85Ohm-diff_PCIE",
        "pattern": "PCIE2_RX1_N"
      },
      {
        "netclass": "85Ohm-diff_PCIE",
        "pattern": "PCIE2_RX1_P"
      },
      {
        "netclass": "85Ohm-diff_PCIE",
        "pattern": "PCIE2_TX0_N"
      },
      {
        "netclass": "85Ohm-diff_PCIE",
        "pattern": "PCIE2_TX0_P"
      },
      {
        "netclass": "85Ohm-diff_PCIE",
        "pattern": "PCIE2_TX1_N"
      },
      {
        "netclass": "85Ohm-diff_PCIE",
        "pattern": "PCIE2_TX1_P"
      },
      {
        "netclass": "85Ohm-diff_PCIE",
        "pattern": "PCIE3_CLK_N"
      },
      {
        "netclass": "85Ohm-diff_PCIE",
        "pattern": "PCIE3_CLK_P"
      },
      {
        "netclass": "85Ohm-diff_USB_2.0",
        "pattern": "/Peripherals/USB_CONN_N"
      },
      {
        "netclass": "85Ohm-diff_USB_2.0",
        "pattern": "/Peripherals/USB_CONN_P"
      },
      {
        "netclass": "85Ohm-diff_USB_2.0",
        "pattern": "USB0_D_N"
      },
      {
        "netclass": "85Ohm-diff_USB_2.0",
        "pattern": "USB0_D_P"
      },
      {
        "netclass": "85Ohm-diff_USB_2.0",
        "pattern": "USB1_D_N"
      },
      {
        "netclass": "85Ohm-diff_USB_2.0",
        "pattern": "USB1_D_P"
      },
      {
        "netclass": "85Ohm-diff_USB_2.0",
        "pattern": "USB2_D_N"
      },
      {
        "netclass": "85Ohm-diff_USB_2.0",
        "pattern": "USB2_D_P"
      },
      {
        "netclass": "85Ohm-diff_USB_SS",
        "pattern": "/Peripherals/USBSS2_TX_CONN_N"
      },
      {
        "netclass": "85Ohm-diff_USB_SS",
        "pattern": "/Peripherals/USBSS2_TX_CONN_P"
      },
      {
        "netclass": "85Ohm-diff_USB_SS",
        "pattern": "/USB Debug, DP/USBC0_CONN_TX1_N"
      },
      {
        "netclass": "85Ohm-diff_USB_SS",
        "pattern": "/USB Debug, DP/USBC0_CONN_TX1_P"
      },
      {
        "netclass": "85Ohm-diff_USB_SS",
        "pattern": "/USB Debug, DP/USBC0_CONN_TX2_N"
      },
      {
        "netclass": "85Ohm-diff_USB_SS",
        "pattern": "/USB Debug, DP/USBC0_CONN_TX2_P"
      },
      {
        "netclass": "85Ohm-diff_USB_SS",
        "pattern": "/USB Debug, DP/USBC0_RX1_N"
      },
      {
        "netclass": "85Ohm-diff_USB_SS",
        "pattern": "/USB Debug, DP/USBC0_RX1_P"
      },
      {
        "netclass": "85Ohm-diff_USB_SS",
        "pattern": "/USB Debug, DP/USBC0_RX2_N"
      },
      {
        "netclass": "85Ohm-diff_USB_SS",
        "pattern": "/USB Debug, DP/USBC0_RX2_P"
      },
      {
        "netclass": "85Ohm-diff_USB_SS",
        "pattern": "/USB Debug, DP/USBC0_TX1_N"
      },
      {
        "netclass": "85Ohm-diff_USB_SS",
        "pattern": "/USB Debug, DP/USBC0_TX1_P"
      },
      {
        "netclass": "85Ohm-diff_USB_SS",
        "pattern": "/USB Debug, DP/USBC0_TX2_N"
      },
      {
        "netclass": "85Ohm-diff_USB_SS",
        "pattern": "/USB Debug, DP/USBC0_TX2_P"
      },
      {
        "netclass": "85Ohm-diff_USB_SS",
        "pattern": "/USB Debug, DP/USBSS0_RX_C_N"
      },
      {
        "netclass": "85Ohm-diff_USB_SS",
        "pattern": "/USB Debug, DP/USBSS0_RX_C_P"
      },
      {
        "netclass": "85Ohm-diff_USB_SS",
        "pattern": "/USB Debug, DP/USBSS0_TX_C_N"
      },
      {
        "netclass": "85Ohm-diff_USB_SS",
        "pattern": "/USB Debug, DP/USBSS0_TX_C_P"
      },
      {
        "netclass": "85Ohm-diff_USB_SS",
        "pattern": "/USB3/USBC1_CONN_TX1_N"
      },
      {
        "netclass": "85Ohm-diff_USB_SS",
        "pattern": "/USB3/USBC1_CONN_TX1_P"
      },
      {
        "netclass": "85Ohm-diff_USB_SS",
        "pattern": "/USB3/USBC1_CONN_TX2_N"
      },
      {
        "netclass": "85Ohm-diff_USB_SS",
        "pattern": "/USB3/USBC1_CONN_TX2_P"
      },
      {
        "netclass": "85Ohm-diff_USB_SS",
        "pattern": "/USB3/USBC1_RX1_N"
      },
      {
        "netclass": "85Ohm-diff_USB_SS",
        "pattern": "/USB3/USBC1_RX1_P"
      },
      {
        "netclass": "85Ohm-diff_USB_SS",
        "pattern": "/USB3/USBC1_RX2_N"
      },
      {
        "netclass": "85Ohm-diff_USB_SS",
        "pattern": "/USB3/USBC1_RX2_P"
      },
      {
        "netclass": "85Ohm-diff_USB_SS",
        "pattern": "/USB3/USBC1_TX1_N"
      },
      {
        "netclass": "85Ohm-diff_USB_SS",
        "pattern": "/USB3/USBC1_TX1_P"
      },
      {
        "netclass": "85Ohm-diff_USB_SS",
        "pattern": "/USB3/USBC1_TX2_N"
      },
      {
        "netclass": "85Ohm-diff_USB_SS",
        "pattern": "/USB3/USBC1_TX2_P"
      },
      {
        "netclass": "85Ohm-diff_USB_SS",
        "pattern": "/USB3/USBSS1_C_RX_N"
      },
      {
        "netclass": "85Ohm-diff_USB_SS",
        "pattern": "/USB3/USBSS1_C_RX_P"
      },
      {
        "netclass": "85Ohm-diff_USB_SS",
        "pattern": "/USB3/USBSS1_C_TX_N"
      },
      {
        "netclass": "85Ohm-diff_USB_SS",
        "pattern": "/USB3/USBSS1_C_TX_P"
      },
      {
        "netclass": "85Ohm-diff_USB_SS",
        "pattern": "USBSS0_RX_N"
      },
      {
        "netclass": "85Ohm-diff_USB_SS",
        "pattern": "USBSS0_RX_P"
      },
      {
        "netclass": "85Ohm-diff_USB_SS",
        "pattern": "USBSS0_TX_N"
      },
      {
        "netclass": "85Ohm-diff_USB_SS",
        "pattern": "USBSS0_TX_P"
      },
      {
        "netclass": "85Ohm-diff_USB_SS",
        "pattern": "USBSS1_RX_N"
      },
      {
        "netclass": "85Ohm-diff_USB_SS",
        "pattern": "USBSS1_RX_P"
      },
      {
        "netclass": "85Ohm-diff_USB_SS",
        "pattern": "USBSS1_TX_N"
      },
      {
        "netclass": "85Ohm-diff_USB_SS",
        "pattern": "USBSS1_TX_P"
      },
      {
        "netclass": "85Ohm-diff_USB_SS",
        "pattern": "USBSS2_RX_N"
      },
      {
        "netclass": "85Ohm-diff_USB_SS",
        "pattern": "USBSS2_RX_P"
      },
      {
        "netclass": "85Ohm-diff_USB_SS",
        "pattern": "USBSS2_TX_N"
      },
      {
        "netclass": "85Ohm-diff_USB_SS",
        "pattern": "USBSS2_TX_P"
      },
      {
        "netclass": "PoE",
        "pattern": "/Ethernet/*"
      },
      {
        "netclass": "PoE",
        "pattern": "GNDD"
      },
      {
        "netclass": "PoE",
        "pattern": "*unconnected-(U22*"
      }
    ]
  },
  "pcbnew": {
    "last_paths": {
      "gencad": "",
      "idf": "",
      "netlist": "",
      "plot": "",
      "pos_files": "",
      "specctra_dsn": "",
      "step": "",
      "svg": "",
      "vrml": "jetson-orin-baseboard.wrl"
    },
    "page_layout_descr_file": ""
  },
  "schematic": {
    "annotate_start_num": 0,
    "bom_export_filename": "",
    "bom_fmt_presets": [],
    "bom_fmt_settings": {
      "field_delimiter": ",",
      "keep_line_breaks": false,
      "keep_tabs": false,
      "name": "CSV",
      "ref_delimiter": ",",
      "ref_range_delimiter": "",
      "string_delimiter": "\""
    },
    "bom_presets": [],
    "bom_settings": {
      "exclude_dnp": false,
      "fields_ordered": [
        {
          "group_by": false,
          "label": "Reference",
          "name": "Reference",
          "show": true
        },
        {
          "group_by": true,
          "label": "Value",
          "name": "Value",
          "show": true
        },
        {
          "group_by": false,
          "label": "Datasheet",
          "name": "Datasheet",
          "show": true
        },
        {
          "group_by": false,
          "label": "Footprint",
          "name": "Footprint",
          "show": true
        },
        {
          "group_by": false,
          "label": "Qty",
          "name": "${QUANTITY}",
          "show": true
        },
        {
          "group_by": true,
          "label": "DNP",
          "name": "${DNP}",
          "show": true
        },
        {
          "group_by": false,
          "label": "#",
          "name": "${ITEM_NUMBER}",
          "show": false
        },
        {
          "group_by": false,
          "label": "Alternatives 100W",
          "name": "Alternatives 100W",
          "show": false
        },
        {
          "group_by": false,
          "label": "Alternatives 120W",
          "name": "Alternatives 120W",
          "show": false
        },
        {
          "group_by": false,
          "label": "Alternatives 50W",
          "name": "Alternatives 50W",
          "show": false
        },
        {
          "group_by": false,
          "label": "Alternatives 75W",
          "name": "Alternatives 75W",
          "show": false
        },
        {
          "group_by": false,
          "label": "Author",
          "name": "Author",
          "show": false
        },
        {
          "group_by": false,
          "label": "Color",
          "name": "Color",
          "show": false
        },
        {
          "group_by": false,
          "label": "Current",
          "name": "Current",
          "show": false
        },
        {
          "group_by": false,
          "label": "Dielectric",
          "name": "Dielectric",
          "show": false
        },
        {
          "group_by": false,
          "label": "Displayed name",
          "name": "Displayed name",
          "show": false
        },
        {
          "group_by": false,
          "label": "IMax",
          "name": "IMax",
          "show": false
        },
        {
          "group_by": false,
          "label": "ISat",
          "name": "ISat",
          "show": false
        },
        {
          "group_by": false,
          "label": "License",
          "name": "License",
          "show": false
        },
        {
          "group_by": false,
          "label": "MPN",
          "name": "MPN",
          "show": false
        },
        {
          "group_by": false,
          "label": "Manufacturer",
          "name": "Manufacturer",
          "show": false
        },
        {
          "group_by": false,
          "label": "Max. Curr.",
          "name": "Max. Curr.",
          "show": false
        },
        {
          "group_by": false,
          "label": "Pitch",
          "name": "Pitch",
          "show": false
        },
        {
          "group_by": false,
          "label": "Public",
          "name": "Public",
          "show": false
        },
        {
          "group_by": false,
          "label": "Size",
          "name": "Size",
          "show": false
        },
        {
          "group_by": false,
          "label": "Tolerance",
          "name": "Tolerance",
          "show": false
        },
        {
          "group_by": false,
          "label": "Val",
          "name": "Val",
          "show": false
        },
        {
          "group_by": false,
          "label": "Voltage",
          "name": "Voltage",
          "show": false
        },
        {
          "group_by": false,
          "label": "Description",
          "name": "Description",
          "show": false
        }
      ],
      "filter_string": "",
      "group_symbols": true,
      "name": "",
      "sort_asc": true,
      "sort_field": "Reference"
    },
    "connection_grid_size": 50.0,
    "drawing": {
      "dashed_lines_dash_length_ratio": 12.0,
      "dashed_lines_gap_length_ratio": 3.0,
      "default_line_thickness": 6.0,
      "default_text_size": 50.0,
      "field_names": [],
      "intersheets_ref_own_page": false,
      "intersheets_ref_prefix": "Pg.",
      "intersheets_ref_short": false,
      "intersheets_ref_show": true,
      "intersheets_ref_suffix": "",
      "junction_size_choice": 3,
      "label_size_ratio": 0.375,
      "operating_point_overlay_i_precision": 3,
      "operating_point_overlay_i_range": "~A",
      "operating_point_overlay_v_precision": 3,
      "operating_point_overlay_v_range": "~V",
      "overbar_offset_ratio": 1.23,
      "pin_symbol_size": 25.0,
      "text_offset_ratio": 0.15
    },
    "legacy_lib_dir": "",
    "legacy_lib_list": [],
    "meta": {
      "version": 1
    },
    "net_format_name": "",
    "ngspice": {
      "fix_include_paths": true,
      "fix_passive_vals": false,
      "meta": {
        "version": 0
      },
      "model_mode": 0,
      "workbook_filename": ""
    },
    "page_layout_descr_file": "",
    "plot_directory": "./doc",
    "spice_adjust_passive_values": false,
    "spice_current_sheet_as_root": false,
    "spice_external_command": "spice \"%I\"",
    "spice_model_current_sheet_as_root": true,
    "spice_save_all_currents": false,
    "spice_save_all_dissipations": false,
    "spice_save_all_voltages": false,
    "subpart_first_id": 65,
    "subpart_id_separator": 0
  },
  "sheets": [
    [
      "",
      "Root"
    ],
    [
      "",
      "SoM"
    ],
    [
      "",
      "M.2"
    ],
    [
      "",
      "USB Debug, DP"
    ],
    [
      "",
      "USB3"
    ],
    [
      "",
      "HDMI"
    ],
    [
      "",
      "Ethernet"
    ],
    [
      "",
      "CSI"
    ],
    [
      "",
      "Peripherals"
    ],
    [
      "",
      "Supply"
    ]
  ],
  "text_variables": {}
}
